(kicad_pcb
	(version 20260206)
	(generator "pcbnew")
	(generator_version "10.0")
	(general
		(thickness 1.6)
		(legacy_teardrops no)
	)
	(paper "A4")
	(title_block
		(title "panther-plus-userver — 13130-1b_20150205.brd")
		(comment 1 "Honey Badger (Wiwynn) / footprints 606-611 of 1509")
	)
	(layers
		(0 "F.Cu" signal "TOP")
		(4 "In1.Cu" signal "L2")
		(6 "In2.Cu" signal "L3")
		(8 "In3.Cu" signal "L4")
		(10 "In4.Cu" signal "L5")
		(12 "In5.Cu" signal "L6")
		(14 "In6.Cu" signal "L7")
		(16 "In7.Cu" signal "L8")
		(18 "In8.Cu" signal "L9")
		(20 "In9.Cu" signal "L10")
		(22 "In10.Cu" signal "L11")
		(2 "B.Cu" signal "BOTTOM")
		(9 "F.Adhes" user "F.Adhesive")
		(11 "B.Adhes" user "B.Adhesive")
		(13 "F.Paste" user "Package Geometry/Pastemask Top")
		(15 "B.Paste" user "Package Geometry/Pastemask Bottom")
		(5 "F.SilkS" user "Ref Des/Silkscreen Top")
		(7 "B.SilkS" user "Ref Des/Silkscreen Bottom")
		(1 "F.Mask" user "Board Geometry/Soldermask Top")
		(3 "B.Mask" user "Board Geometry/Soldermask Bottom")
		(17 "Dwgs.User" user "User.Drawings")
		(19 "Cmts.User" user "User.Comments")
		(21 "Eco1.User" user "User.Eco1")
		(23 "Eco2.User" user "User.Eco2")
		(25 "Edge.Cuts" user "Board Geometry/Outline")
		(27 "Margin" user)
		(31 "F.CrtYd" user "Package Geometry/Place Bound Top")
		(29 "B.CrtYd" user "Package Geometry/Place Bound Bottom")
		(35 "F.Fab" user "Ref Des/Assembly Top")
		(33 "B.Fab" user "Ref Des/Assembly Bottom")
	)
	(footprint ""
		(layer "F.Cu")
		(at 202.954128 -11.946128 -90)
		(property "Reference" "CN3"
			(at 0 0 270)
			(layer "F.SilkS")
			(hide yes)
			(effects
				(font
					(size 1.27 1.27)
				)
			)
		)
		(property "Value" "FOX-CONN10A-S8-GP"
			(at -7.874 -9.0932 270)
			(unlocked yes)
			(layer "F.Fab")
			(hide yes)
			(effects
				(font
					(size 1.016 1.016)
					(thickness 0.1524)
				)
			)
		)
		(property "Device Type" "HC3105F"
			(at -7.874 -10.6172 270)
			(unlocked yes)
			(layer "F.Fab")
			(hide yes)
			(effects
				(font
					(size 1.016 1.016)
					(thickness 0.1524)
				)
			)
		)
		(duplicate_pad_numbers_are_jumpers no)
		(fp_line
			(start -6.604 2.8702)
			(end -5.334 2.8702)
			(stroke
				(width 0.4064)
				(type default)
			)
			(layer "F.SilkS")
		)
		(fp_line
			(start -6.477 2.7432)
			(end 6.477 2.7432)
			(stroke
				(width 0.1524)
				(type default)
			)
			(layer "F.SilkS")
		)
		(fp_line
			(start 6.477 2.7432)
			(end 6.477 -2.7432)
			(stroke
				(width 0.1524)
				(type default)
			)
			(layer "F.SilkS")
		)
		(fp_line
			(start -6.604 1.6002)
			(end -6.604 2.8702)
			(stroke
				(width 0.4064)
				(type default)
			)
			(layer "F.SilkS")
		)
		(fp_line
			(start -6.477 -2.7432)
			(end -6.477 2.7432)
			(stroke
				(width 0.1524)
				(type default)
			)
			(layer "F.SilkS")
		)
		(fp_line
			(start 6.477 -2.7432)
			(end -6.477 -2.7432)
			(stroke
				(width 0.1524)
				(type default)
			)
			(layer "F.SilkS")
		)
		(fp_circle
			(center -5.08 1.27)
			(end -5.08 0.1524)
			(stroke
				(width 0.3048)
				(type default)
			)
			(fill no)
			(layer "F.SilkS")
		)
		(fp_circle
			(center -2.54 1.27)
			(end -2.54 0.1524)
			(stroke
				(width 0.3048)
				(type default)
			)
			(fill no)
			(layer "F.SilkS")
		)
		(fp_circle
			(center 0 1.27)
			(end 0 0.1524)
			(stroke
				(width 0.3048)
				(type default)
			)
			(fill no)
			(layer "F.SilkS")
		)
		(fp_circle
			(center 2.54 1.27)
			(end 2.54 0.1524)
			(stroke
				(width 0.3048)
				(type default)
			)
			(fill no)
			(layer "F.SilkS")
		)
		(fp_circle
			(center 5.08 1.27)
			(end 5.08 0.1524)
			(stroke
				(width 0.3048)
				(type default)
			)
			(fill no)
			(layer "F.SilkS")
		)
		(fp_circle
			(center -5.08 -1.27)
			(end -5.08 -2.3876)
			(stroke
				(width 0.3048)
				(type default)
			)
			(fill no)
			(layer "F.SilkS")
		)
		(fp_circle
			(center -2.54 -1.27)
			(end -2.54 -2.3876)
			(stroke
				(width 0.3048)
				(type default)
			)
			(fill no)
			(layer "F.SilkS")
		)
		(fp_circle
			(center 0 -1.27)
			(end 0 -2.3876)
			(stroke
				(width 0.3048)
				(type default)
			)
			(fill no)
			(layer "F.SilkS")
		)
		(fp_circle
			(center 2.54 -1.27)
			(end 2.54 -2.3876)
			(stroke
				(width 0.3048)
				(type default)
			)
			(fill no)
			(layer "F.SilkS")
		)
		(fp_circle
			(center 5.08 -1.27)
			(end 5.08 -2.3876)
			(stroke
				(width 0.3048)
				(type default)
			)
			(fill no)
			(layer "F.SilkS")
		)
		(fp_rect
			(start -6.223 2.4892)
			(end 6.223 -2.4892)
			(stroke
				(width 0)
				(type default)
			)
			(fill no)
			(layer "F.CrtYd")
		)
		(fp_poly
			(pts
				(xy 6.731 -2.4892) (xy -6.223 -2.4892) (xy -6.223 2.4892) (xy 6.223 2.4892) (xy 6.223 -2.4765) (xy 6.731 -2.4765)
				(xy 6.731 2.9972) (xy -6.731 2.9972) (xy -6.731 -2.9972) (xy 6.731 -2.9972)
			)
			(stroke
				(width 0)
				(type default)
			)
			(fill no)
			(layer "F.CrtYd")
		)
		(fp_rect
			(start -6.731 2.9972)
			(end 6.731 -2.9972)
			(stroke
				(width 0)
				(type default)
			)
			(fill no)
			(layer "F.Fab")
		)
		(pad "1" thru_hole circle
			(at -5.08 1.27 270)
			(size 1.524 1.524)
			(drill 1.1176)
			(layers "*.Cu" "*.Mask")
			(remove_unused_layers no)
			(net "JTAG_PLD_TCK")
			(clearance 0.1524)
			(thermal_gap 0.1524)
		)
		(pad "2" thru_hole circle
			(at -5.08 -1.27 270)
			(size 1.524 1.524)
			(drill 1.1176)
			(layers "*.Cu" "*.Mask")
			(remove_unused_layers no)
			(net "GND")
			(clearance 0.1524)
			(thermal_gap 0.1524)
		)
		(pad "3" thru_hole circle
			(at -2.54 1.27 270)
			(size 1.524 1.524)
			(drill 1.1176)
			(layers "*.Cu" "*.Mask")
			(remove_unused_layers no)
			(net "JTAG_CPU_PLD_TDO")
			(clearance 0.1524)
			(thermal_gap 0.1524)
		)
		(pad "4" thru_hole circle
			(at -2.54 -1.27 270)
			(size 1.524 1.524)
			(drill 1.1176)
			(layers "*.Cu" "*.Mask")
			(remove_unused_layers no)
			(net "P3V3_STBY")
			(clearance 0.1524)
			(thermal_gap 0.1524)
		)
		(pad "5" thru_hole circle
			(at 0 1.27 270)
			(size 1.524 1.524)
			(drill 1.1176)
			(layers "*.Cu" "*.Mask")
			(remove_unused_layers no)
			(net "JTAG_PLD_TMS")
			(clearance 0.1524)
			(thermal_gap 0.1524)
		)
		(pad "6" thru_hole circle
			(at 0 -1.27 270)
			(size 1.524 1.524)
			(drill 1.1176)
			(layers "*.Cu" "*.Mask")
			(remove_unused_layers no)
			(net "C_NCE_R#")
			(clearance 0.1524)
			(thermal_gap 0.1524)
		)
		(pad "7" thru_hole circle
			(at 2.54 1.27 270)
			(size 1.524 1.524)
			(drill 1.1176)
			(layers "*.Cu" "*.Mask")
			(remove_unused_layers no)
			(net "Net_89")
			(clearance 0.1524)
			(thermal_gap 0.1524)
		)
		(pad "8" thru_hole circle
			(at 2.54 -1.27 270)
			(size 1.524 1.524)
			(drill 1.1176)
			(layers "*.Cu" "*.Mask")
			(remove_unused_layers no)
			(net "JTAG_RST#")
			(clearance 0.1524)
			(thermal_gap 0.1524)
		)
		(pad "9" thru_hole circle
			(at 5.08 1.27 270)
			(size 1.524 1.524)
			(drill 1.1176)
			(layers "*.Cu" "*.Mask")
			(remove_unused_layers no)
			(net "JTAG_PLD_TDI")
			(clearance 0.1524)
			(thermal_gap 0.1524)
		)
		(pad "10" thru_hole circle
			(at 5.08 -1.27 270)
			(size 1.524 1.524)
			(drill 1.1176)
			(layers "*.Cu" "*.Mask")
			(remove_unused_layers no)
			(net "GND")
			(clearance 0.1524)
			(thermal_gap 0.1524)
		)
	)
	(footprint ""
		(layer "F.Cu")
		(at 5.1562 -43.0022 90)
		(property "Reference" "R3"
			(at 0 0 90)
			(layer "F.SilkS")
			(hide yes)
			(effects
				(font
					(size 1.27 1.27)
				)
			)
		)
		(property "Value" "4K7R2F-GP"
			(at 0.064008 -3.993896 90)
			(unlocked yes)
			(layer "F.Fab")
			(hide yes)
			(effects
				(font
					(size 1.016 1.016)
					(thickness 0.1524)
				)
			)
		)
		(property "Device Type" "R402H16"
			(at 0.064008 -5.517896 90)
			(unlocked yes)
			(layer "F.Fab")
			(hide yes)
			(effects
				(font
					(size 1.016 1.016)
					(thickness 0.1524)
				)
			)
		)
		(duplicate_pad_numbers_are_jumpers no)
		(fp_rect
			(start -0.381 0.8382)
			(end 0.381 -0.8382)
			(stroke
				(width 0)
				(type default)
			)
			(fill no)
			(layer "F.CrtYd")
		)
		(fp_rect
			(start -0.381 0.8382)
			(end 0.381 -0.8382)
			(stroke
				(width 0)
				(type default)
			)
			(fill no)
			(layer "F.Fab")
		)
		(pad "1" smd custom
			(at 0 -0.4318 90)
			(size 0.127 0.127)
			(layers "F.Cu" "F.Mask" "F.Paste")
			(net "P3V3_STBY")
			(options
				(clearance outline)
				(anchor circle)
			)
			(primitives
				(gr_poly
					(pts
						(arc
							(start -0.2032 -0.2794)
							(mid -0.239121 -0.264521)
							(end -0.254 -0.2286)
						)
						(arc
							(start -0.254 0.2286)
							(mid -0.239121 0.264521)
							(end -0.2032 0.2794)
						)
						(arc
							(start 0.2032 0.2794)
							(mid 0.239121 0.264521)
							(end 0.254 0.2286)
						)
						(arc
							(start 0.254 -0.2286)
							(mid 0.239121 -0.264521)
							(end 0.2032 -0.2794)
						)
					)
					(width 0)
					(fill yes)
				)
			)
		)
		(pad "2" smd custom
			(at 0 0.4318 90)
			(size 0.127 0.127)
			(layers "F.Cu" "F.Mask" "F.Paste")
			(net "TEMP_1_ALERT#")
			(options
				(clearance outline)
				(anchor circle)
			)
			(primitives
				(gr_poly
					(pts
						(arc
							(start -0.2032 -0.2794)
							(mid -0.239121 -0.264521)
							(end -0.254 -0.2286)
						)
						(arc
							(start -0.254 0.2286)
							(mid -0.239121 0.264521)
							(end -0.2032 0.2794)
						)
						(arc
							(start 0.2032 0.2794)
							(mid 0.239121 0.264521)
							(end 0.254 0.2286)
						)
						(arc
							(start 0.254 -0.2286)
							(mid 0.239121 -0.264521)
							(end 0.2032 -0.2794)
						)
					)
					(width 0)
					(fill yes)
				)
			)
		)
	)
	(footprint ""
		(layer "F.Cu")
		(at 157.226 -52.832 -90)
		(property "Reference" "C311"
			(at 0 0 270)
			(layer "F.SilkS")
			(hide yes)
			(effects
				(font
					(size 1.27 1.27)
				)
			)
		)
		(property "Value" "SCD1U16V2KX-3GP"
			(at 1.8923 -1.2065 270)
			(unlocked yes)
			(layer "F.Fab")
			(hide yes)
			(effects
				(font
					(size 1.016 1.016)
					(thickness 0.1524)
				)
			)
		)
		(property "Device Type" "C402H22"
			(at 1.8923 -2.7305 270)
			(unlocked yes)
			(layer "F.Fab")
			(hide yes)
			(effects
				(font
					(size 1.016 1.016)
					(thickness 0.1524)
				)
			)
		)
		(duplicate_pad_numbers_are_jumpers no)
		(fp_rect
			(start -0.381 0.7366)
			(end 0.381 -0.7366)
			(stroke
				(width 0)
				(type default)
			)
			(fill no)
			(layer "F.CrtYd")
		)
		(fp_rect
			(start -0.381 0.7366)
			(end 0.381 -0.7366)
			(stroke
				(width 0)
				(type default)
			)
			(fill no)
			(layer "F.Fab")
		)
		(pad "1" smd custom
			(at 0 -0.4572 270)
			(size 0.1143 0.1143)
			(layers "F.Cu" "F.Mask" "F.Paste")
			(net "P3V3_STBY")
			(options
				(clearance outline)
				(anchor circle)
			)
			(primitives
				(gr_poly
					(pts
						(arc
							(start -0.254 -0.1778)
							(mid -0.239121 -0.213721)
							(end -0.2032 -0.2286)
						)
						(arc
							(start 0.2032 -0.2286)
							(mid 0.239121 -0.213721)
							(end 0.254 -0.1778)
						)
						(arc
							(start 0.254 0.1778)
							(mid 0.239121 0.213721)
							(end 0.2032 0.2286)
						)
						(arc
							(start -0.2032 0.2286)
							(mid -0.239121 0.213721)
							(end -0.254 0.1778)
						)
					)
					(width 0)
					(fill yes)
				)
			)
		)
		(pad "2" smd custom
			(at 0 0.4572 270)
			(size 0.1143 0.1143)
			(layers "F.Cu" "F.Mask" "F.Paste")
			(net "GND")
			(options
				(clearance outline)
				(anchor circle)
			)
			(primitives
				(gr_poly
					(pts
						(arc
							(start -0.254 -0.1778)
							(mid -0.239121 -0.213721)
							(end -0.2032 -0.2286)
						)
						(arc
							(start 0.2032 -0.2286)
							(mid 0.239121 -0.213721)
							(end 0.254 -0.1778)
						)
						(arc
							(start 0.254 0.1778)
							(mid 0.239121 0.213721)
							(end 0.2032 0.2286)
						)
						(arc
							(start -0.2032 0.2286)
							(mid -0.239121 0.213721)
							(end -0.254 0.1778)
						)
					)
					(width 0)
					(fill yes)
				)
			)
		)
	)
	(footprint ""
		(layer "F.Cu")
		(at 31.623 -33.02)
		(property "Reference" "R274"
			(at 0 0 0)
			(layer "F.SilkS")
			(hide yes)
			(effects
				(font
					(size 1.27 1.27)
				)
			)
		)
		(property "Value" "1KR2F-3-GP"
			(at 0.064008 -3.993896 0)
			(unlocked yes)
			(layer "F.Fab")
			(hide yes)
			(effects
				(font
					(size 1.016 1.016)
					(thickness 0.1524)
				)
			)
		)
		(property "Device Type" "R402H16"
			(at 0.064008 -5.517896 0)
			(unlocked yes)
			(layer "F.Fab")
			(hide yes)
			(effects
				(font
					(size 1.016 1.016)
					(thickness 0.1524)
				)
			)
		)
		(duplicate_pad_numbers_are_jumpers no)
		(fp_rect
			(start -0.381 0.8382)
			(end 0.381 -0.8382)
			(stroke
				(width 0)
				(type default)
			)
			(fill no)
			(layer "F.CrtYd")
		)
		(fp_rect
			(start -0.381 0.8382)
			(end 0.381 -0.8382)
			(stroke
				(width 0)
				(type default)
			)
			(fill no)
			(layer "F.Fab")
		)
		(pad "1" smd custom
			(at 0 -0.4318)
			(size 0.127 0.127)
			(layers "F.Cu" "F.Mask" "F.Paste")
			(net "P3V3")
			(options
				(clearance outline)
				(anchor circle)
			)
			(primitives
				(gr_poly
					(pts
						(arc
							(start -0.2032 -0.2794)
							(mid -0.239121 -0.264521)
							(end -0.254 -0.2286)
						)
						(arc
							(start -0.254 0.2286)
							(mid -0.239121 0.264521)
							(end -0.2032 0.2794)
						)
						(arc
							(start 0.2032 0.2794)
							(mid 0.239121 0.264521)
							(end 0.254 0.2286)
						)
						(arc
							(start 0.254 -0.2286)
							(mid 0.239121 -0.264521)
							(end 0.2032 -0.2794)
						)
					)
					(width 0)
					(fill yes)
				)
			)
		)
		(pad "2" smd custom
			(at 0 0.4318)
			(size 0.127 0.127)
			(layers "F.Cu" "F.Mask" "F.Paste")
			(net "XDP_RST_BTN_R#")
			(options
				(clearance outline)
				(anchor circle)
			)
			(primitives
				(gr_poly
					(pts
						(arc
							(start -0.2032 -0.2794)
							(mid -0.239121 -0.264521)
							(end -0.254 -0.2286)
						)
						(arc
							(start -0.254 0.2286)
							(mid -0.239121 0.264521)
							(end -0.2032 0.2794)
						)
						(arc
							(start 0.2032 0.2794)
							(mid 0.239121 0.264521)
							(end 0.254 0.2286)
						)
						(arc
							(start 0.254 -0.2286)
							(mid 0.239121 -0.264521)
							(end 0.2032 -0.2794)
						)
					)
					(width 0)
					(fill yes)
				)
			)
		)
	)
	(footprint ""
		(layer "F.Cu")
		(at 78.232 -65.913)
		(property "Reference" "R189"
			(at 0 0 0)
			(layer "F.SilkS")
			(hide yes)
			(effects
				(font
					(size 1.27 1.27)
				)
			)
		)
		(property "Value" "0R2J-2-GP"
			(at 0.064008 -3.993896 0)
			(unlocked yes)
			(layer "F.Fab")
			(hide yes)
			(effects
				(font
					(size 1.016 1.016)
					(thickness 0.1524)
				)
			)
		)
		(property "Device Type" "R402H16"
			(at 0.064008 -5.517896 0)
			(unlocked yes)
			(layer "F.Fab")
			(hide yes)
			(effects
				(font
					(size 1.016 1.016)
					(thickness 0.1524)
				)
			)
		)
		(duplicate_pad_numbers_are_jumpers no)
		(fp_rect
			(start -0.381 0.8382)
			(end 0.381 -0.8382)
			(stroke
				(width 0)
				(type default)
			)
			(fill no)
			(layer "F.CrtYd")
		)
		(fp_rect
			(start -0.381 0.8382)
			(end 0.381 -0.8382)
			(stroke
				(width 0)
				(type default)
			)
			(fill no)
			(layer "F.Fab")
		)
		(pad "1" smd custom
			(at 0 -0.4318)
			(size 0.127 0.127)
			(layers "F.Cu" "F.Mask" "F.Paste")
			(net "PVCCP")
			(options
				(clearance outline)
				(anchor circle)
			)
			(primitives
				(gr_poly
					(pts
						(arc
							(start -0.2032 -0.2794)
							(mid -0.239121 -0.264521)
							(end -0.254 -0.2286)
						)
						(arc
							(start -0.254 0.2286)
							(mid -0.239121 0.264521)
							(end -0.2032 0.2794)
						)
						(arc
							(start 0.2032 0.2794)
							(mid 0.239121 0.264521)
							(end 0.254 0.2286)
						)
						(arc
							(start 0.254 -0.2286)
							(mid 0.239121 -0.264521)
							(end 0.2032 -0.2794)
						)
					)
					(width 0)
					(fill yes)
				)
			)
		)
		(pad "2" smd custom
			(at 0 0.4318)
			(size 0.127 0.127)
			(layers "F.Cu" "F.Mask" "F.Paste")
			(net "PVCCP_SENSE")
			(options
				(clearance outline)
				(anchor circle)
			)
			(primitives
				(gr_poly
					(pts
						(arc
							(start -0.2032 -0.2794)
							(mid -0.239121 -0.264521)
							(end -0.254 -0.2286)
						)
						(arc
							(start -0.254 0.2286)
							(mid -0.239121 0.264521)
							(end -0.2032 0.2794)
						)
						(arc
							(start 0.2032 0.2794)
							(mid 0.239121 0.264521)
							(end 0.254 0.2286)
						)
						(arc
							(start 0.254 -0.2286)
							(mid 0.239121 -0.264521)
							(end 0.2032 -0.2794)
						)
					)
					(width 0)
					(fill yes)
				)
			)
		)
	)
	(footprint ""
		(layer "F.Cu")
		(at 7.5184 -21.463 -90)
		(property "Reference" "PR111"
			(at 0 0 270)
			(layer "F.SilkS")
			(hide yes)
			(effects
				(font
					(size 1.27 1.27)
				)
			)
		)
		(property "Value" "187KR2F-GP"
			(at 1.7907 -1.1176 270)
			(unlocked yes)
			(layer "F.Fab")
			(hide yes)
			(effects
				(font
					(size 1.016 1.016)
					(thickness 0.1524)
				)
			)
		)
		(property "Device Type" "R402H16"
			(at 1.7907 -2.6416 270)
			(unlocked yes)
			(layer "F.Fab")
			(hide yes)
			(effects
				(font
					(size 1.016 1.016)
					(thickness 0.1524)
				)
			)
		)
		(duplicate_pad_numbers_are_jumpers no)
		(fp_rect
			(start -0.381 0.8382)
			(end 0.381 -0.8382)
			(stroke
				(width 0)
				(type default)
			)
			(fill no)
			(layer "F.CrtYd")
		)
		(fp_rect
			(start -0.381 0.8382)
			(end 0.381 -0.8382)
			(stroke
				(width 0)
				(type default)
			)
			(fill no)
			(layer "F.Fab")
		)
		(pad "1" smd custom
			(at 0 -0.4318 270)
			(size 0.127 0.127)
			(layers "F.Cu" "F.Mask" "F.Paste")
			(net "P1V0_RF")
			(options
				(clearance outline)
				(anchor circle)
			)
			(primitives
				(gr_poly
					(pts
						(arc
							(start -0.2032 -0.2794)
							(mid -0.239121 -0.264521)
							(end -0.254 -0.2286)
						)
						(arc
							(start -0.254 0.2286)
							(mid -0.239121 0.264521)
							(end -0.2032 0.2794)
						)
						(arc
							(start 0.2032 0.2794)
							(mid 0.239121 0.264521)
							(end 0.254 0.2286)
						)
						(arc
							(start 0.254 -0.2286)
							(mid 0.239121 -0.264521)
							(end 0.2032 -0.2794)
						)
					)
					(width 0)
					(fill yes)
				)
			)
		)
		(pad "2" smd custom
			(at 0 0.4318 270)
			(size 0.127 0.127)
			(layers "F.Cu" "F.Mask" "F.Paste")
			(net "AGND_P1V0")
			(options
				(clearance outline)
				(anchor circle)
			)
			(primitives
				(gr_poly
					(pts
						(arc
							(start -0.2032 -0.2794)
							(mid -0.239121 -0.264521)
							(end -0.254 -0.2286)
						)
						(arc
							(start -0.254 0.2286)
							(mid -0.239121 0.264521)
							(end -0.2032 0.2794)
						)
						(arc
							(start 0.2032 0.2794)
							(mid 0.239121 0.264521)
							(end 0.254 0.2286)
						)
						(arc
							(start 0.254 -0.2286)
							(mid 0.239121 -0.264521)
							(end 0.2032 -0.2794)
						)
					)
					(width 0)
					(fill yes)
				)
			)
		)
	)
)
